(kicad_pcb
	(version 20260206)
	(generator "pcbnew")
	(generator_version "10.0")
	(general
		(thickness 1.6)
		(legacy_teardrops no)
	)
	(paper "A4")
	(title_block
		(title "Bryce Canyon_SCC_16316-1_OCP.brd")
		(comment 1 "Bryce Canyon / footprints 361-369 of 1561")
	)
	(layers
		(0 "F.Cu" signal "TOP")
		(4 "In1.Cu" signal "L2GND")
		(6 "In2.Cu" signal "L3")
		(8 "In3.Cu" signal "L4VCC")
		(10 "In4.Cu" signal "L5VCC")
		(12 "In5.Cu" signal "L6")
		(14 "In6.Cu" signal "L7GND")
		(2 "B.Cu" signal "BOTTOM")
		(9 "F.Adhes" user "F.Adhesive")
		(11 "B.Adhes" user "B.Adhesive")
		(13 "F.Paste" user "Package Geometry/Pastemask Top")
		(15 "B.Paste" user "Package Geometry/Pastemask Bottom")
		(5 "F.SilkS" user "Ref Des/Silkscreen Top")
		(7 "B.SilkS" user "Ref Des/Silkscreen Bottom")
		(1 "F.Mask" user "Board Geometry/Soldermask Top")
		(3 "B.Mask" user "Board Geometry/Soldermask Bottom")
		(17 "Dwgs.User" user "User.Drawings")
		(19 "Cmts.User" user "User.Comments")
		(21 "Eco1.User" user "User.Eco1")
		(23 "Eco2.User" user "User.Eco2")
		(25 "Edge.Cuts" user "Board Geometry/Outline")
		(27 "Margin" user)
		(31 "F.CrtYd" user "Package Geometry/Place Bound Top")
		(29 "B.CrtYd" user "Package Geometry/Place Bound Bottom")
		(35 "F.Fab" user "Ref Des/Assembly Top")
		(33 "B.Fab" user "Ref Des/Assembly Bottom")
	)
	(footprint ""
		(layer "F.Cu")
		(at 182.1561 -114.80673)
		(property "Reference" "R99"
			(at 0 0 0)
			(layer "F.SilkS")
			(hide yes)
			(effects
				(font
					(size 1.27 1.27)
				)
			)
		)
		(property "Value" "3K57R2F-GP"
			(at 0.064008 -3.993896 0)
			(unlocked yes)
			(layer "F.Fab")
			(hide yes)
			(effects
				(font
					(size 1.016 1.016)
					(thickness 0.1524)
				)
			)
		)
		(property "Device Type" "R402H16"
			(at 0.064008 -5.517896 0)
			(unlocked yes)
			(layer "F.Fab")
			(hide yes)
			(effects
				(font
					(size 1.016 1.016)
					(thickness 0.1524)
				)
			)
		)
		(duplicate_pad_numbers_are_jumpers no)
		(fp_line
			(start -0.508 -0.9398)
			(end -0.508 0.9398)
			(stroke
				(width 0.1524)
				(type default)
			)
			(layer "F.SilkS")
		)
		(fp_line
			(start 0.508 -0.9398)
			(end -0.508 -0.9398)
			(stroke
				(width 0.1524)
				(type default)
			)
			(layer "F.SilkS")
		)
		(fp_rect
			(start -0.508 0.9398)
			(end 0.508 -0.9398)
			(stroke
				(width 0)
				(type default)
			)
			(fill no)
			(layer "F.CrtYd")
		)
		(fp_rect
			(start -0.508 0.9398)
			(end 0.508 -0.9398)
			(stroke
				(width 0)
				(type default)
			)
			(fill no)
			(layer "F.Fab")
		)
		(pad "1" smd custom
			(at 0 -0.4445)
			(size 0.1397 0.1397)
			(layers "F.Cu" "F.Mask" "F.Paste")
			(net "P1V8_E_OUT")
			(options
				(clearance outline)
				(anchor circle)
			)
			(primitives
				(gr_poly
					(pts
						(arc
							(start -0.1778 -0.2794)
							(mid -0.249642 -0.249642)
							(end -0.2794 -0.1778)
						)
						(arc
							(start -0.2794 0.1778)
							(mid -0.249642 0.249642)
							(end -0.1778 0.2794)
						)
						(arc
							(start 0.1778 0.2794)
							(mid 0.249642 0.249642)
							(end 0.2794 0.1778)
						)
						(arc
							(start 0.2794 -0.1778)
							(mid 0.249642 -0.249642)
							(end 0.1778 -0.2794)
						)
					)
					(width 0)
					(fill yes)
				)
			)
		)
		(pad "2" smd custom
			(at 0 0.4445)
			(size 0.1397 0.1397)
			(layers "F.Cu" "F.Mask" "F.Paste")
			(net "P1V8_E_FB")
			(options
				(clearance outline)
				(anchor circle)
			)
			(primitives
				(gr_poly
					(pts
						(arc
							(start -0.1778 -0.2794)
							(mid -0.249642 -0.249642)
							(end -0.2794 -0.1778)
						)
						(arc
							(start -0.2794 0.1778)
							(mid -0.249642 0.249642)
							(end -0.1778 0.2794)
						)
						(arc
							(start 0.1778 0.2794)
							(mid 0.249642 0.249642)
							(end 0.2794 0.1778)
						)
						(arc
							(start 0.2794 -0.1778)
							(mid 0.249642 -0.249642)
							(end 0.1778 -0.2794)
						)
					)
					(width 0)
					(fill yes)
				)
			)
		)
	)
	(footprint ""
		(layer "F.Cu")
		(at 119.963184 -86.995)
		(property "Reference" "R38"
			(at 0 0 0)
			(layer "F.SilkS")
			(hide yes)
			(effects
				(font
					(size 1.27 1.27)
				)
			)
		)
		(property "Value" "4K7R2F-GP"
			(at 0.064008 -3.993896 0)
			(unlocked yes)
			(layer "F.Fab")
			(hide yes)
			(effects
				(font
					(size 1.016 1.016)
					(thickness 0.1524)
				)
			)
		)
		(property "Device Type" "R402H16"
			(at 0.064008 -5.517896 0)
			(unlocked yes)
			(layer "F.Fab")
			(hide yes)
			(effects
				(font
					(size 1.016 1.016)
					(thickness 0.1524)
				)
			)
		)
		(duplicate_pad_numbers_are_jumpers no)
		(fp_line
			(start -0.508 -0.9398)
			(end -0.508 0.9398)
			(stroke
				(width 0.1524)
				(type default)
			)
			(layer "F.SilkS")
		)
		(fp_line
			(start 0.508 -0.9398)
			(end -0.508 -0.9398)
			(stroke
				(width 0.1524)
				(type default)
			)
			(layer "F.SilkS")
		)
		(fp_rect
			(start -0.508 0.9398)
			(end 0.508 -0.9398)
			(stroke
				(width 0)
				(type default)
			)
			(fill no)
			(layer "F.CrtYd")
		)
		(fp_rect
			(start -0.508 0.9398)
			(end 0.508 -0.9398)
			(stroke
				(width 0)
				(type default)
			)
			(fill no)
			(layer "F.Fab")
		)
		(pad "1" smd custom
			(at 0 -0.4445)
			(size 0.1397 0.1397)
			(layers "F.Cu" "F.Mask" "F.Paste")
			(net "P1V8_E")
			(options
				(clearance outline)
				(anchor circle)
			)
			(primitives
				(gr_poly
					(pts
						(arc
							(start -0.1778 -0.2794)
							(mid -0.249642 -0.249642)
							(end -0.2794 -0.1778)
						)
						(arc
							(start -0.2794 0.1778)
							(mid -0.249642 0.249642)
							(end -0.1778 0.2794)
						)
						(arc
							(start 0.1778 0.2794)
							(mid 0.249642 0.249642)
							(end 0.2794 0.1778)
						)
						(arc
							(start 0.2794 -0.1778)
							(mid 0.249642 -0.249642)
							(end 0.1778 -0.2794)
						)
					)
					(width 0)
					(fill yes)
				)
			)
		)
		(pad "2" smd custom
			(at 0 0.4445)
			(size 0.1397 0.1397)
			(layers "F.Cu" "F.Mask" "F.Paste")
			(net "EXP_GPIO15")
			(options
				(clearance outline)
				(anchor circle)
			)
			(primitives
				(gr_poly
					(pts
						(arc
							(start -0.1778 -0.2794)
							(mid -0.249642 -0.249642)
							(end -0.2794 -0.1778)
						)
						(arc
							(start -0.2794 0.1778)
							(mid -0.249642 0.249642)
							(end -0.1778 0.2794)
						)
						(arc
							(start 0.1778 0.2794)
							(mid 0.249642 0.249642)
							(end 0.2794 0.1778)
						)
						(arc
							(start 0.2794 -0.1778)
							(mid 0.249642 -0.249642)
							(end 0.1778 -0.2794)
						)
					)
					(width 0)
					(fill yes)
				)
			)
		)
	)
	(footprint ""
		(layer "F.Cu")
		(at 21.7678 -47.0154)
		(property "Reference" "R15"
			(at 0 0 0)
			(layer "F.SilkS")
			(hide yes)
			(effects
				(font
					(size 1.27 1.27)
				)
			)
		)
		(property "Value" "4K12R2F-3-GP"
			(at 0.064008 -3.993896 0)
			(unlocked yes)
			(layer "F.Fab")
			(hide yes)
			(effects
				(font
					(size 1.016 1.016)
					(thickness 0.1524)
				)
			)
		)
		(property "Device Type" "R402H16"
			(at 0.064008 -5.517896 0)
			(unlocked yes)
			(layer "F.Fab")
			(hide yes)
			(effects
				(font
					(size 1.016 1.016)
					(thickness 0.1524)
				)
			)
		)
		(duplicate_pad_numbers_are_jumpers no)
		(fp_line
			(start -0.508 -0.9398)
			(end -0.508 0.9398)
			(stroke
				(width 0.1524)
				(type default)
			)
			(layer "F.SilkS")
		)
		(fp_line
			(start 0.508 -0.9398)
			(end -0.508 -0.9398)
			(stroke
				(width 0.1524)
				(type default)
			)
			(layer "F.SilkS")
		)
		(fp_rect
			(start -0.508 0.9398)
			(end 0.508 -0.9398)
			(stroke
				(width 0)
				(type default)
			)
			(fill no)
			(layer "F.CrtYd")
		)
		(fp_rect
			(start -0.508 0.9398)
			(end 0.508 -0.9398)
			(stroke
				(width 0)
				(type default)
			)
			(fill no)
			(layer "F.Fab")
		)
		(pad "1" smd custom
			(at 0 -0.4445)
			(size 0.1397 0.1397)
			(layers "F.Cu" "F.Mask" "F.Paste")
			(net "MB0_CM_OV_R")
			(options
				(clearance outline)
				(anchor circle)
			)
			(primitives
				(gr_poly
					(pts
						(arc
							(start -0.1778 -0.2794)
							(mid -0.249642 -0.249642)
							(end -0.2794 -0.1778)
						)
						(arc
							(start -0.2794 0.1778)
							(mid -0.249642 0.249642)
							(end -0.1778 0.2794)
						)
						(arc
							(start 0.1778 0.2794)
							(mid 0.249642 0.249642)
							(end 0.2794 0.1778)
						)
						(arc
							(start 0.2794 -0.1778)
							(mid 0.249642 -0.249642)
							(end 0.1778 -0.2794)
						)
					)
					(width 0)
					(fill yes)
				)
			)
		)
		(pad "2" smd custom
			(at 0 0.4445)
			(size 0.1397 0.1397)
			(layers "F.Cu" "F.Mask" "F.Paste")
			(net "AGND_CURRENT_MON")
			(options
				(clearance outline)
				(anchor circle)
			)
			(primitives
				(gr_poly
					(pts
						(arc
							(start -0.1778 -0.2794)
							(mid -0.249642 -0.249642)
							(end -0.2794 -0.1778)
						)
						(arc
							(start -0.2794 0.1778)
							(mid -0.249642 0.249642)
							(end -0.1778 0.2794)
						)
						(arc
							(start 0.1778 0.2794)
							(mid 0.249642 0.249642)
							(end 0.2794 0.1778)
						)
						(arc
							(start 0.2794 -0.1778)
							(mid 0.249642 -0.249642)
							(end 0.1778 -0.2794)
						)
					)
					(width 0)
					(fill yes)
				)
			)
		)
	)
	(footprint ""
		(layer "F.Cu")
		(at 158.5087 -78.864714 -90)
		(property "Reference" "R331"
			(at 0 0 270)
			(layer "F.SilkS")
			(hide yes)
			(effects
				(font
					(size 1.27 1.27)
				)
			)
		)
		(property "Value" "4K7R2F-GP"
			(at 0.064008 -3.993896 270)
			(unlocked yes)
			(layer "F.Fab")
			(hide yes)
			(effects
				(font
					(size 1.016 1.016)
					(thickness 0.1524)
				)
			)
		)
		(property "Device Type" "R402H16"
			(at 0.064008 -5.517896 270)
			(unlocked yes)
			(layer "F.Fab")
			(hide yes)
			(effects
				(font
					(size 1.016 1.016)
					(thickness 0.1524)
				)
			)
		)
		(duplicate_pad_numbers_are_jumpers no)
		(fp_line
			(start -0.508 -0.9398)
			(end -0.508 0.9398)
			(stroke
				(width 0.1524)
				(type default)
			)
			(layer "F.SilkS")
		)
		(fp_line
			(start 0.508 -0.9398)
			(end -0.508 -0.9398)
			(stroke
				(width 0.1524)
				(type default)
			)
			(layer "F.SilkS")
		)
		(fp_rect
			(start -0.508 0.9398)
			(end 0.508 -0.9398)
			(stroke
				(width 0)
				(type default)
			)
			(fill no)
			(layer "F.CrtYd")
		)
		(fp_rect
			(start -0.508 0.9398)
			(end 0.508 -0.9398)
			(stroke
				(width 0)
				(type default)
			)
			(fill no)
			(layer "F.Fab")
		)
		(pad "1" smd custom
			(at 0 -0.4445 270)
			(size 0.1397 0.1397)
			(layers "F.Cu" "F.Mask" "F.Paste")
			(net "P3V3")
			(options
				(clearance outline)
				(anchor circle)
			)
			(primitives
				(gr_poly
					(pts
						(arc
							(start -0.1778 -0.2794)
							(mid -0.249642 -0.249642)
							(end -0.2794 -0.1778)
						)
						(arc
							(start -0.2794 0.1778)
							(mid -0.249642 0.249642)
							(end -0.1778 0.2794)
						)
						(arc
							(start 0.1778 0.2794)
							(mid 0.249642 0.249642)
							(end 0.2794 0.1778)
						)
						(arc
							(start 0.2794 -0.1778)
							(mid 0.249642 -0.249642)
							(end 0.1778 -0.2794)
						)
					)
					(width 0)
					(fill yes)
				)
			)
		)
		(pad "2" smd custom
			(at 0 0.4445 270)
			(size 0.1397 0.1397)
			(layers "F.Cu" "F.Mask" "F.Paste")
			(net "VOL_SEN2_ALERT")
			(options
				(clearance outline)
				(anchor circle)
			)
			(primitives
				(gr_poly
					(pts
						(arc
							(start -0.1778 -0.2794)
							(mid -0.249642 -0.249642)
							(end -0.2794 -0.1778)
						)
						(arc
							(start -0.2794 0.1778)
							(mid -0.249642 0.249642)
							(end -0.1778 0.2794)
						)
						(arc
							(start 0.1778 0.2794)
							(mid 0.249642 0.249642)
							(end 0.2794 0.1778)
						)
						(arc
							(start 0.2794 -0.1778)
							(mid 0.249642 -0.249642)
							(end 0.1778 -0.2794)
						)
					)
					(width 0)
					(fill yes)
				)
			)
		)
	)
	(footprint ""
		(layer "F.Cu")
		(at 123.317 -111.28248)
		(property "Reference" "TP23"
			(at 0 0 0)
			(layer "F.SilkS")
			(hide yes)
			(effects
				(font
					(size 1.27 1.27)
				)
			)
		)
		(property "Value" "TPAD28-2-GP"
			(at -0.0127 -1.6637 0)
			(unlocked yes)
			(layer "F.Fab")
			(hide yes)
			(effects
				(font
					(size 1.016 1.016)
					(thickness 0.1524)
				)
			)
		)
		(property "Device Type" "TPAD28"
			(at -0.0127 -3.1877 0)
			(unlocked yes)
			(layer "F.Fab")
			(hide yes)
			(effects
				(font
					(size 1.016 1.016)
					(thickness 0.1524)
				)
			)
		)
		(duplicate_pad_numbers_are_jumpers no)
		(fp_poly
			(pts
				(arc
					(start 0.3556 0)
					(mid -0.3556 0)
					(end 0.3556 0)
				)
			)
			(stroke
				(width 0)
				(type default)
			)
			(fill no)
			(layer "F.CrtYd")
		)
		(fp_poly
			(pts
				(arc
					(start 0.6096 0)
					(mid -0.6096 0)
					(end 0.6096 0)
				)
			)
			(stroke
				(width 0)
				(type default)
			)
			(fill no)
			(layer "F.Fab")
		)
		(pad "1" smd circle
			(at 0 0)
			(size 0.7112 0.7112)
			(layers "F.Cu" "F.Mask" "F.Paste")
			(net "INT_B1_CONN1")
		)
	)
	(footprint ""
		(layer "F.Cu")
		(at 38.9382 -43.4086)
		(property "Reference" "C668"
			(at 0 0 0)
			(layer "F.SilkS")
			(hide yes)
			(effects
				(font
					(size 1.27 1.27)
				)
			)
		)
		(property "Value" "SC10U16V5KX-7-GP-U"
			(at -0.0762 -6.1214 0)
			(unlocked yes)
			(layer "F.Fab")
			(hide yes)
			(effects
				(font
					(size 1.016 1.016)
					(thickness 0.1524)
				)
			)
		)
		(property "Device Type" "C805H58"
			(at -0.0762 -8.1534 0)
			(unlocked yes)
			(layer "F.Fab")
			(hide yes)
			(effects
				(font
					(size 1.016 1.016)
					(thickness 0.1524)
				)
			)
		)
		(duplicate_pad_numbers_are_jumpers no)
		(fp_line
			(start 0.635 0)
			(end -0.635 0)
			(stroke
				(width 0.508)
				(type default)
			)
			(layer "F.SilkS")
		)
		(fp_rect
			(start -0.9652 1.778)
			(end 0.9652 -1.778)
			(stroke
				(width 0)
				(type default)
			)
			(fill no)
			(layer "F.CrtYd")
		)
		(fp_poly
			(pts
				(xy -0.9652 -1.778) (xy 0.9652 -1.778) (xy 0.9652 1.778) (xy -0.9652 1.778)
			)
			(stroke
				(width 0)
				(type default)
			)
			(fill no)
			(layer "F.Fab")
		)
		(pad "1" smd rect
			(at 0 -0.9652)
			(size 1.397 1.143)
			(layers "F.Cu" "F.Mask" "F.Paste")
			(net "P12V_STBY_VIN_Q7")
		)
		(pad "2" smd rect
			(at 0 0.9652)
			(size 1.397 1.143)
			(layers "F.Cu" "F.Mask" "F.Paste")
			(net "GND")
		)
	)
	(footprint ""
		(layer "F.Cu")
		(at 161.29 -111.125 180)
		(property "Reference" "L6"
			(at 0 0 180)
			(layer "F.SilkS")
			(hide yes)
			(effects
				(font
					(size 1.27 1.27)
				)
			)
		)
		(property "Value" "BLM21PG220SN1DGP"
			(at 0.0254 -5.6896 180)
			(unlocked yes)
			(layer "F.Fab")
			(hide yes)
			(effects
				(font
					(size 1.016 1.016)
					(thickness 0.1524)
				)
			)
		)
		(property "Device Type" "L20125H42"
			(at 0.0254 -7.5946 180)
			(unlocked yes)
			(layer "F.Fab")
			(hide yes)
			(effects
				(font
					(size 1.016 1.016)
					(thickness 0.1524)
				)
			)
		)
		(duplicate_pad_numbers_are_jumpers no)
		(fp_line
			(start 0.9144 1.7018)
			(end 0.9144 -1.7018)
			(stroke
				(width 0.1524)
				(type default)
			)
			(layer "F.SilkS")
		)
		(fp_line
			(start 0.9144 -1.7018)
			(end -0.9144 -1.7018)
			(stroke
				(width 0.1524)
				(type default)
			)
			(layer "F.SilkS")
		)
		(fp_line
			(start -0.9144 1.7018)
			(end 0.9144 1.7018)
			(stroke
				(width 0.1524)
				(type default)
			)
			(layer "F.SilkS")
		)
		(fp_line
			(start -0.9144 -1.7018)
			(end -0.9144 1.7018)
			(stroke
				(width 0.1524)
				(type default)
			)
			(layer "F.SilkS")
		)
		(fp_rect
			(start -1.0033 1.778)
			(end 1.0033 -1.778)
			(stroke
				(width 0)
				(type default)
			)
			(fill no)
			(layer "F.CrtYd")
		)
		(fp_poly
			(pts
				(xy -1.0033 -1.778) (xy 1.0033 -1.778) (xy 1.0033 1.778) (xy -1.0033 1.778)
			)
			(stroke
				(width 0)
				(type default)
			)
			(fill no)
			(layer "F.Fab")
		)
		(pad "1" smd rect
			(at 0 -0.9652 180)
			(size 1.397 1.143)
			(layers "F.Cu" "F.Mask" "F.Paste")
			(net "P12V_STBY_SCC")
		)
		(pad "2" smd rect
			(at 0 0.9652 180)
			(size 1.397 1.143)
			(layers "F.Cu" "F.Mask" "F.Paste")
			(net "P12V_STBY_VIN_U11")
		)
	)
	(footprint ""
		(layer "F.Cu")
		(at 165.4556 -86.106 90)
		(property "Reference" "C637"
			(at 0 0 90)
			(layer "F.SilkS")
			(hide yes)
			(effects
				(font
					(size 1.27 1.27)
				)
			)
		)
		(property "Value" "SC10U16V5KX-7-GP-U"
			(at -0.0762 -6.1214 90)
			(unlocked yes)
			(layer "F.Fab")
			(hide yes)
			(effects
				(font
					(size 1.016 1.016)
					(thickness 0.1524)
				)
			)
		)
		(property "Device Type" "C805H58"
			(at -0.0762 -8.1534 90)
			(unlocked yes)
			(layer "F.Fab")
			(hide yes)
			(effects
				(font
					(size 1.016 1.016)
					(thickness 0.1524)
				)
			)
		)
		(duplicate_pad_numbers_are_jumpers no)
		(fp_line
			(start 0.635 0)
			(end -0.635 0)
			(stroke
				(width 0.508)
				(type default)
			)
			(layer "F.SilkS")
		)
		(fp_rect
			(start -0.9652 1.778)
			(end 0.9652 -1.778)
			(stroke
				(width 0)
				(type default)
			)
			(fill no)
			(layer "F.CrtYd")
		)
		(fp_poly
			(pts
				(xy -0.9652 -1.778) (xy 0.9652 -1.778) (xy 0.9652 1.778) (xy -0.9652 1.778)
			)
			(stroke
				(width 0)
				(type default)
			)
			(fill no)
			(layer "F.Fab")
		)
		(pad "1" smd rect
			(at 0 -0.9652 90)
			(size 1.397 1.143)
			(layers "F.Cu" "F.Mask" "F.Paste")
			(net "P12V_SYBY_VDD_U6")
		)
		(pad "2" smd rect
			(at 0 0.9652 90)
			(size 1.397 1.143)
			(layers "F.Cu" "F.Mask" "F.Paste")
			(net "GND")
		)
	)
	(footprint ""
		(layer "F.Cu")
		(at 164.2364 -93.5736)
		(property "Reference" "C644"
			(at 0 0 0)
			(layer "F.SilkS")
			(hide yes)
			(effects
				(font
					(size 1.27 1.27)
				)
			)
		)
		(property "Value" "SC10U16V5KX-7-GP-U"
			(at -0.0762 -6.1214 0)
			(unlocked yes)
			(layer "F.Fab")
			(hide yes)
			(effects
				(font
					(size 1.016 1.016)
					(thickness 0.1524)
				)
			)
		)
		(property "Device Type" "C805H58"
			(at -0.0762 -8.1534 0)
			(unlocked yes)
			(layer "F.Fab")
			(hide yes)
			(effects
				(font
					(size 1.016 1.016)
					(thickness 0.1524)
				)
			)
		)
		(duplicate_pad_numbers_are_jumpers no)
		(fp_line
			(start 0.635 0)
			(end -0.635 0)
			(stroke
				(width 0.508)
				(type default)
			)
			(layer "F.SilkS")
		)
		(fp_rect
			(start -0.9652 1.778)
			(end 0.9652 -1.778)
			(stroke
				(width 0)
				(type default)
			)
			(fill no)
			(layer "F.CrtYd")
		)
		(fp_poly
			(pts
				(xy -0.9652 -1.778) (xy 0.9652 -1.778) (xy 0.9652 1.778) (xy -0.9652 1.778)
			)
			(stroke
				(width 0)
				(type default)
			)
			(fill no)
			(layer "F.Fab")
		)
		(pad "1" smd rect
			(at 0 -0.9652)
			(size 1.397 1.143)
			(layers "F.Cu" "F.Mask" "F.Paste")
			(net "P12V_SYBY_VDD_U6")
		)
		(pad "2" smd rect
			(at 0 0.9652)
			(size 1.397 1.143)
			(layers "F.Cu" "F.Mask" "F.Paste")
			(net "GND")
		)
	)
)
